(kicad_pcb
	(version 20260206)
	(generator "pcbnew")
	(generator_version "10.0")
	(general
		(thickness 1.6)
		(legacy_teardrops no)
	)
	(paper "A4")
	(title_block
		(title "Bryce Canyon_F.DPB_16315-1-OCP.brd")
		(comment 1 "Bryce Canyon / footprints 64-72 of 2223")
	)
	(layers
		(0 "F.Cu" signal "TOP")
		(4 "In1.Cu" signal "L2GND")
		(6 "In2.Cu" signal "L3")
		(8 "In3.Cu" signal "L4GND")
		(10 "In4.Cu" signal "L5")
		(12 "In5.Cu" signal "L6VCC")
		(14 "In6.Cu" signal "L7VCC")
		(16 "In7.Cu" signal "L8")
		(18 "In8.Cu" signal "L9GND")
		(20 "In9.Cu" signal "L10")
		(22 "In10.Cu" signal "L11GND")
		(2 "B.Cu" signal "BOTTOM")
		(9 "F.Adhes" user "F.Adhesive")
		(11 "B.Adhes" user "B.Adhesive")
		(13 "F.Paste" user "Package Geometry/Pastemask Top")
		(15 "B.Paste" user "Package Geometry/Pastemask Bottom")
		(5 "F.SilkS" user "Ref Des/Silkscreen Top")
		(7 "B.SilkS" user "Ref Des/Silkscreen Bottom")
		(1 "F.Mask" user "Board Geometry/Soldermask Top")
		(3 "B.Mask" user "Board Geometry/Soldermask Bottom")
		(17 "Dwgs.User" user "User.Drawings")
		(19 "Cmts.User" user "User.Comments")
		(21 "Eco1.User" user "User.Eco1")
		(23 "Eco2.User" user "User.Eco2")
		(25 "Edge.Cuts" user "Board Geometry/Outline")
		(27 "Margin" user)
		(31 "F.CrtYd" user "Package Geometry/Place Bound Top")
		(29 "B.CrtYd" user "Package Geometry/Place Bound Bottom")
		(35 "F.Fab" user "Ref Des/Assembly Top")
		(33 "B.Fab" user "Ref Des/Assembly Bottom")
	)
	(footprint ""
		(layer "F.Cu")
		(at 114.216942 -278.822404 90)
		(property "Reference" "D3"
			(at 0 0 90)
			(layer "F.SilkS")
			(hide yes)
			(effects
				(font
					(size 1.27 1.27)
				)
			)
		)
		(property "Value" "RB551V30-GP"
			(at 0 -6.7818 90)
			(unlocked yes)
			(layer "F.Fab")
			(hide yes)
			(effects
				(font
					(size 1.016 1.016)
					(thickness 0.1524)
				)
			)
		)
		(property "Device Type" "SOD323AKH38"
			(at 0 -8.6868 90)
			(unlocked yes)
			(layer "F.Fab")
			(hide yes)
			(effects
				(font
					(size 1.016 1.016)
					(thickness 0.1524)
				)
			)
		)
		(duplicate_pad_numbers_are_jumpers no)
		(fp_line
			(start 0.889 -1.9304)
			(end 0.889 2.159)
			(stroke
				(width 0.1524)
				(type default)
			)
			(layer "F.SilkS")
		)
		(fp_line
			(start -0.889 -1.9304)
			(end 0.889 -1.9304)
			(stroke
				(width 0.1524)
				(type default)
			)
			(layer "F.SilkS")
		)
		(fp_line
			(start 0.762 2.0574)
			(end -0.762 2.0574)
			(stroke
				(width 0.508)
				(type default)
			)
			(layer "F.SilkS")
		)
		(fp_line
			(start 0.889 2.159)
			(end -0.889 2.159)
			(stroke
				(width 0.1524)
				(type default)
			)
			(layer "F.SilkS")
		)
		(fp_line
			(start -0.889 2.159)
			(end -0.889 -1.9304)
			(stroke
				(width 0.1524)
				(type default)
			)
			(layer "F.SilkS")
		)
		(fp_rect
			(start -1.016 2.3114)
			(end 1.016 -2.0066)
			(stroke
				(width 0)
				(type default)
			)
			(fill no)
			(layer "F.CrtYd")
		)
		(fp_poly
			(pts
				(xy -1.016 -2.0066) (xy 1.016 -2.0066) (xy 1.016 2.3114) (xy -1.016 2.3114)
			)
			(stroke
				(width 0)
				(type default)
			)
			(fill no)
			(layer "F.Fab")
		)
		(pad "A" smd rect
			(at 0 -1.143 90)
			(size 0.5588 1.016)
			(layers "F.Cu" "F.Mask" "F.Paste")
			(net "SW_HDD_R3")
		)
		(pad "K" smd rect
			(at 0 1.143 90)
			(size 0.5588 1.016)
			(layers "F.Cu" "F.Mask" "F.Paste")
			(net "SW_HDD_N3")
		)
	)
	(footprint ""
		(layer "F.Cu")
		(at 365.136938 -69.44995 -90)
		(property "Reference" "R844"
			(at 0 0 270)
			(layer "F.SilkS")
			(hide yes)
			(effects
				(font
					(size 1.27 1.27)
				)
			)
		)
		(property "Value" "2R6F-GP"
			(at -0.0508 -4.8514 270)
			(unlocked yes)
			(layer "F.Fab")
			(hide yes)
			(effects
				(font
					(size 1.016 1.016)
					(thickness 0.1524)
				)
			)
		)
		(property "Device Type" "R1206H26"
			(at 0 -6.3754 270)
			(unlocked yes)
			(layer "F.Fab")
			(hide yes)
			(effects
				(font
					(size 1.016 1.016)
					(thickness 0.1524)
				)
			)
		)
		(duplicate_pad_numbers_are_jumpers no)
		(fp_line
			(start -1.016 2.2352)
			(end -1.016 -2.2352)
			(stroke
				(width 0.1524)
				(type default)
			)
			(layer "F.SilkS")
		)
		(fp_line
			(start 1.016 2.2352)
			(end -1.016 2.2352)
			(stroke
				(width 0.1524)
				(type default)
			)
			(layer "F.SilkS")
		)
		(fp_line
			(start -1.016 -2.2352)
			(end 1.016 -2.2352)
			(stroke
				(width 0.1524)
				(type default)
			)
			(layer "F.SilkS")
		)
		(fp_line
			(start 1.016 -2.2352)
			(end 1.016 2.2352)
			(stroke
				(width 0.1524)
				(type default)
			)
			(layer "F.SilkS")
		)
		(fp_rect
			(start -1.0922 2.3114)
			(end 1.0922 -2.3114)
			(stroke
				(width 0)
				(type default)
			)
			(fill no)
			(layer "F.CrtYd")
		)
		(fp_poly
			(pts
				(xy -1.0922 -2.3114) (xy 1.0922 -2.3114) (xy 1.0922 2.3114) (xy -1.0922 2.3114)
			)
			(stroke
				(width 0)
				(type default)
			)
			(fill no)
			(layer "F.Fab")
		)
		(pad "1" smd rect
			(at 0 -1.397 270)
			(size 1.651 1.27)
			(layers "F.Cu" "F.Mask" "F.Paste")
			(net "P12V_HDD31")
		)
		(pad "2" smd rect
			(at 0 1.397 270)
			(size 1.651 1.27)
			(layers "F.Cu" "F.Mask" "F.Paste")
			(net "12V_PRE_31")
		)
	)
	(footprint ""
		(layer "F.Cu")
		(at 438.2389 -162.749992 -90)
		(property "Reference" "VIA24"
			(at 0 0 270)
			(layer "F.SilkS")
			(hide yes)
			(effects
				(font
					(size 1.27 1.27)
				)
			)
		)
		(property "Value" "100OHM-8L-1D6MM-L18L16-GP"
			(at -3.7211 -4.5085 270)
			(unlocked yes)
			(layer "F.Fab")
			(hide yes)
			(effects
				(font
					(size 1.016 1.016)
					(thickness 0.1524)
				)
			)
		)
		(property "Device Type" "VIA-PCIE-4P-394076"
			(at -3.7211 -6.0325 270)
			(unlocked yes)
			(layer "F.Fab")
			(hide yes)
			(effects
				(font
					(size 1.016 1.016)
					(thickness 0.1524)
				)
			)
		)
		(duplicate_pad_numbers_are_jumpers no)
		(fp_rect
			(start -1.9685 0.381)
			(end 1.9685 -0.381)
			(stroke
				(width 0)
				(type default)
			)
			(fill no)
			(layer "F.CrtYd")
		)
		(fp_rect
			(start -1.9685 0.381)
			(end 1.9685 -0.381)
			(stroke
				(width 0)
				(type default)
			)
			(fill no)
			(layer "F.Fab")
		)
		(pad "1" thru_hole circle
			(at -1.5875 0 270)
			(size 0.508 0.508)
			(drill 0.254)
			(layers "*.Cu" "*.Mask")
			(remove_unused_layers no)
			(net "GND")
			(clearance 0.127)
			(thermal_gap 0.127)
		)
		(pad "2" thru_hole circle
			(at -0.5715 0 270)
			(size 0.508 0.508)
			(drill 0.254)
			(layers "*.Cu" "*.Mask")
			(remove_unused_layers no)
			(net "PHY_DRV_A_TO_SCC_A_22_DP")
			(clearance 0.127)
			(thermal_gap 0.127)
		)
		(pad "3" thru_hole circle
			(at 0.5715 0 270)
			(size 0.508 0.508)
			(drill 0.254)
			(layers "*.Cu" "*.Mask")
			(remove_unused_layers no)
			(net "PHY_DRV_A_TO_SCC_A_22_DN")
			(clearance 0.127)
			(thermal_gap 0.127)
		)
		(pad "4" thru_hole circle
			(at 1.5875 0 270)
			(size 0.508 0.508)
			(drill 0.254)
			(layers "*.Cu" "*.Mask")
			(remove_unused_layers no)
			(net "GND")
			(clearance 0.127)
			(thermal_gap 0.127)
		)
	)
	(footprint ""
		(layer "F.Cu")
		(at 260.874002 -217.894662)
		(property "Reference" "C23"
			(at 0 0 0)
			(layer "F.SilkS")
			(hide yes)
			(effects
				(font
					(size 1.27 1.27)
				)
			)
		)
		(property "Value" "SC1U16V3KX-5GP"
			(at 0 -2.8194 0)
			(unlocked yes)
			(layer "F.Fab")
			(hide yes)
			(effects
				(font
					(size 1.016 1.016)
					(thickness 0.1524)
				)
			)
		)
		(property "Device Type" "C603H36"
			(at 0 -4.3434 0)
			(unlocked yes)
			(layer "F.Fab")
			(hide yes)
			(effects
				(font
					(size 1.016 1.016)
					(thickness 0.1524)
				)
			)
		)
		(duplicate_pad_numbers_are_jumpers no)
		(fp_line
			(start 0.508 0)
			(end -0.508 0)
			(stroke
				(width 0.2032)
				(type default)
			)
			(layer "F.SilkS")
		)
		(fp_rect
			(start -0.5842 1.3335)
			(end 0.5842 -1.3335)
			(stroke
				(width 0)
				(type default)
			)
			(fill no)
			(layer "F.CrtYd")
		)
		(fp_rect
			(start -0.5842 1.3335)
			(end 0.5842 -1.3335)
			(stroke
				(width 0)
				(type default)
			)
			(fill no)
			(layer "F.Fab")
		)
		(pad "1" smd custom
			(at 0 -0.762)
			(size 0.2159 0.2159)
			(layers "F.Cu" "F.Mask" "F.Paste")
			(net "P3V3_STBY_A")
			(options
				(clearance outline)
				(anchor circle)
			)
			(primitives
				(gr_poly
					(pts
						(arc
							(start -0.3302 -0.4318)
							(mid -0.402042 -0.402042)
							(end -0.4318 -0.3302)
						)
						(arc
							(start -0.4318 0.3302)
							(mid -0.402042 0.402042)
							(end -0.3302 0.4318)
						)
						(arc
							(start 0.3302 0.4318)
							(mid 0.402042 0.402042)
							(end 0.4318 0.3302)
						)
						(arc
							(start 0.4318 -0.3302)
							(mid 0.402042 -0.402042)
							(end 0.3302 -0.4318)
						)
					)
					(width 0)
					(fill yes)
				)
			)
		)
		(pad "2" smd custom
			(at 0 0.762)
			(size 0.2159 0.2159)
			(layers "F.Cu" "F.Mask" "F.Paste")
			(net "GND")
			(options
				(clearance outline)
				(anchor circle)
			)
			(primitives
				(gr_poly
					(pts
						(arc
							(start -0.3302 -0.4318)
							(mid -0.402042 -0.402042)
							(end -0.4318 -0.3302)
						)
						(arc
							(start -0.4318 0.3302)
							(mid -0.402042 0.402042)
							(end -0.3302 0.4318)
						)
						(arc
							(start 0.3302 0.4318)
							(mid 0.402042 0.402042)
							(end 0.4318 0.3302)
						)
						(arc
							(start 0.4318 -0.3302)
							(mid 0.402042 -0.402042)
							(end 0.3302 -0.4318)
						)
					)
					(width 0)
					(fill yes)
				)
			)
		)
	)
	(footprint ""
		(layer "F.Cu")
		(at 49.349914 -94.400116)
		(property "Reference" "FLED14"
			(at 0 0 0)
			(layer "F.SilkS")
			(hide yes)
			(effects
				(font
					(size 1.27 1.27)
				)
			)
		)
		(property "Value" "LED-BY-19-GP"
			(at -2.132076 1.414018 0)
			(unlocked yes)
			(layer "F.Fab")
			(hide yes)
			(effects
				(font
					(size 1.016 1.016)
					(thickness 0.1524)
				)
			)
		)
		(property "Device Type" "LED-1615-4PH26"
			(at -2.132076 -0.109982 0)
			(unlocked yes)
			(layer "F.Fab")
			(hide yes)
			(effects
				(font
					(size 1.016 1.016)
					(thickness 0.1524)
				)
			)
		)
		(duplicate_pad_numbers_are_jumpers no)
		(fp_line
			(start -1.2954 0.254)
			(end -1.2954 1.6002)
			(stroke
				(width 0.508)
				(type default)
			)
			(layer "F.SilkS")
		)
		(fp_line
			(start -1.2954 1.6002)
			(end 1.2954 1.6002)
			(stroke
				(width 0.508)
				(type default)
			)
			(layer "F.SilkS")
		)
		(fp_line
			(start -1.1176 -1.4224)
			(end 1.1176 -1.4224)
			(stroke
				(width 0.1524)
				(type default)
			)
			(layer "F.SilkS")
		)
		(fp_line
			(start -1.1176 1.4224)
			(end -1.1176 -1.4224)
			(stroke
				(width 0.1524)
				(type default)
			)
			(layer "F.SilkS")
		)
		(fp_line
			(start 1.1176 -1.4224)
			(end 1.1176 1.4224)
			(stroke
				(width 0.1524)
				(type default)
			)
			(layer "F.SilkS")
		)
		(fp_line
			(start 1.1176 1.4224)
			(end -1.1176 1.4224)
			(stroke
				(width 0.1524)
				(type default)
			)
			(layer "F.SilkS")
		)
		(fp_line
			(start 1.2954 1.6002)
			(end 1.2954 0.254)
			(stroke
				(width 0.508)
				(type default)
			)
			(layer "F.SilkS")
		)
		(fp_rect
			(start -0.7493 0.8001)
			(end 0.7493 -0.8001)
			(stroke
				(width 0)
				(type default)
			)
			(fill no)
			(layer "F.CrtYd")
		)
		(fp_poly
			(pts
				(xy -1.3716 1.6764) (xy -1.3716 -1.6764) (xy 1.3716 -1.6764) (xy 1.3716 0.0635) (xy 0.7493 0.0635)
				(xy 0.7493 -0.8001) (xy -0.7493 -0.8001) (xy -0.7493 0.8001) (xy 0.7493 0.8001) (xy 0.7493 0.0762)
				(xy 1.3716 0.0762) (xy 1.3716 1.6764)
			)
			(stroke
				(width 0)
				(type default)
			)
			(fill no)
			(layer "F.CrtYd")
		)
		(fp_rect
			(start -1.3716 1.6764)
			(end 1.3716 -1.6764)
			(stroke
				(width 0)
				(type default)
			)
			(fill no)
			(layer "F.Fab")
		)
		(pad "1" smd rect
			(at 0.50038 -0.73025)
			(size 0.7112 0.8636)
			(layers "F.Cu" "F.Mask" "F.Paste")
			(net "DRV_ACT_13")
		)
		(pad "2" smd rect
			(at -0.50038 -0.73025)
			(size 0.7112 0.8636)
			(layers "F.Cu" "F.Mask" "F.Paste")
			(net "FLT_HDD13")
		)
		(pad "3" smd rect
			(at 0.50038 0.73025)
			(size 0.7112 0.8636)
			(layers "F.Cu" "F.Mask" "F.Paste")
			(net "DRV_ACT_13_N")
		)
		(pad "4" smd rect
			(at -0.50038 0.73025)
			(size 0.7112 0.8636)
			(layers "F.Cu" "F.Mask" "F.Paste")
			(net "FLT_HDD13_N")
		)
	)
	(footprint ""
		(layer "F.Cu")
		(at 431.962052 -162.792918 90)
		(property "Reference" "D21"
			(at 0 0 90)
			(layer "F.SilkS")
			(hide yes)
			(effects
				(font
					(size 1.27 1.27)
				)
			)
		)
		(property "Value" "RB551V30-GP"
			(at 0 -6.7818 90)
			(unlocked yes)
			(layer "F.Fab")
			(hide yes)
			(effects
				(font
					(size 1.016 1.016)
					(thickness 0.1524)
				)
			)
		)
		(property "Device Type" "SOD323AKH38"
			(at 0 -8.6868 90)
			(unlocked yes)
			(layer "F.Fab")
			(hide yes)
			(effects
				(font
					(size 1.016 1.016)
					(thickness 0.1524)
				)
			)
		)
		(duplicate_pad_numbers_are_jumpers no)
		(fp_line
			(start 0.889 -1.9304)
			(end 0.889 2.159)
			(stroke
				(width 0.1524)
				(type default)
			)
			(layer "F.SilkS")
		)
		(fp_line
			(start -0.889 -1.9304)
			(end 0.889 -1.9304)
			(stroke
				(width 0.1524)
				(type default)
			)
			(layer "F.SilkS")
		)
		(fp_line
			(start 0.762 2.0574)
			(end -0.762 2.0574)
			(stroke
				(width 0.508)
				(type default)
			)
			(layer "F.SilkS")
		)
		(fp_line
			(start 0.889 2.159)
			(end -0.889 2.159)
			(stroke
				(width 0.1524)
				(type default)
			)
			(layer "F.SilkS")
		)
		(fp_line
			(start -0.889 2.159)
			(end -0.889 -1.9304)
			(stroke
				(width 0.1524)
				(type default)
			)
			(layer "F.SilkS")
		)
		(fp_rect
			(start -1.016 2.3114)
			(end 1.016 -2.0066)
			(stroke
				(width 0)
				(type default)
			)
			(fill no)
			(layer "F.CrtYd")
		)
		(fp_poly
			(pts
				(xy -1.016 -2.0066) (xy 1.016 -2.0066) (xy 1.016 2.3114) (xy -1.016 2.3114)
			)
			(stroke
				(width 0)
				(type default)
			)
			(fill no)
			(layer "F.Fab")
		)
		(pad "A" smd rect
			(at 0 -1.143 90)
			(size 0.5588 1.016)
			(layers "F.Cu" "F.Mask" "F.Paste")
			(net "SW_HDD_R21")
		)
		(pad "K" smd rect
			(at 0 1.143 90)
			(size 0.5588 1.016)
			(layers "F.Cu" "F.Mask" "F.Paste")
			(net "SW_HDD_N21")
		)
	)
	(footprint ""
		(layer "F.Cu")
		(at 98.643948 -183.747918)
		(property "Reference" "TP72"
			(at 0 0 0)
			(layer "F.SilkS")
			(hide yes)
			(effects
				(font
					(size 1.27 1.27)
				)
			)
		)
		(property "Value" "TPAD32-GP"
			(at -0.0508 -1.6764 0)
			(unlocked yes)
			(layer "F.Fab")
			(hide yes)
			(effects
				(font
					(size 1.016 1.016)
					(thickness 0.1524)
				)
			)
		)
		(property "Device Type" "TPAD32"
			(at -0.0508 -3.2004 0)
			(unlocked yes)
			(layer "F.Fab")
			(hide yes)
			(effects
				(font
					(size 1.016 1.016)
					(thickness 0.1524)
				)
			)
		)
		(duplicate_pad_numbers_are_jumpers no)
		(fp_poly
			(pts
				(arc
					(start 0.4064 0)
					(mid -0.4064 0)
					(end 0.4064 0)
				)
			)
			(stroke
				(width 0)
				(type default)
			)
			(fill no)
			(layer "F.CrtYd")
		)
		(fp_poly
			(pts
				(arc
					(start 0.7112 0)
					(mid -0.7112 0)
					(end 0.7112 0)
				)
			)
			(stroke
				(width 0)
				(type default)
			)
			(fill no)
			(layer "F.Fab")
		)
		(pad "1" smd circle
			(at 0 0)
			(size 0.8128 0.8128)
			(layers "F.Cu" "F.Mask" "F.Paste")
			(net "ACT_HDD_14")
		)
	)
	(footprint ""
		(layer "F.Cu")
		(at 459.731872 -188.999876 180)
		(property "Reference" "C332"
			(at 0 0 180)
			(layer "F.SilkS")
			(hide yes)
			(effects
				(font
					(size 1.27 1.27)
				)
			)
		)
		(property "Value" "SC4D7U25V5KX-1-GP"
			(at -0.0762 -6.1214 180)
			(unlocked yes)
			(layer "F.Fab")
			(hide yes)
			(effects
				(font
					(size 1.016 1.016)
					(thickness 0.1524)
				)
			)
		)
		(property "Device Type" "C805H58"
			(at -0.0762 -8.1534 180)
			(unlocked yes)
			(layer "F.Fab")
			(hide yes)
			(effects
				(font
					(size 1.016 1.016)
					(thickness 0.1524)
				)
			)
		)
		(duplicate_pad_numbers_are_jumpers no)
		(fp_line
			(start 0.635 0)
			(end -0.635 0)
			(stroke
				(width 0.508)
				(type default)
			)
			(layer "F.SilkS")
		)
		(fp_rect
			(start -0.9652 1.778)
			(end 0.9652 -1.778)
			(stroke
				(width 0)
				(type default)
			)
			(fill no)
			(layer "F.CrtYd")
		)
		(fp_poly
			(pts
				(xy -0.9652 -1.778) (xy 0.9652 -1.778) (xy 0.9652 1.778) (xy -0.9652 1.778)
			)
			(stroke
				(width 0)
				(type default)
			)
			(fill no)
			(layer "F.Fab")
		)
		(pad "1" smd rect
			(at 0 -0.9652 180)
			(size 1.397 1.143)
			(layers "F.Cu" "F.Mask" "F.Paste")
			(net "P12V_HDD22")
		)
		(pad "2" smd rect
			(at 0 0.9652 180)
			(size 1.397 1.143)
			(layers "F.Cu" "F.Mask" "F.Paste")
			(net "GND")
		)
	)
	(footprint ""
		(layer "F.Cu")
		(at 446.1891 -43.939968 90)
		(property "Reference" "VIA15"
			(at 0 0 90)
			(layer "F.SilkS")
			(hide yes)
			(effects
				(font
					(size 1.27 1.27)
				)
			)
		)
		(property "Value" "100OHM-8L-1D6MM-L18L16-GP"
			(at -3.7211 -4.5085 90)
			(unlocked yes)
			(layer "F.Fab")
			(hide yes)
			(effects
				(font
					(size 1.016 1.016)
					(thickness 0.1524)
				)
			)
		)
		(property "Device Type" "VIA-PCIE-4P-394076"
			(at -3.7211 -6.0325 90)
			(unlocked yes)
			(layer "F.Fab")
			(hide yes)
			(effects
				(font
					(size 1.016 1.016)
					(thickness 0.1524)
				)
			)
		)
		(duplicate_pad_numbers_are_jumpers no)
		(fp_rect
			(start -1.9685 0.381)
			(end 1.9685 -0.381)
			(stroke
				(width 0)
				(type default)
			)
			(fill no)
			(layer "F.CrtYd")
		)
		(fp_rect
			(start -1.9685 0.381)
			(end 1.9685 -0.381)
			(stroke
				(width 0)
				(type default)
			)
			(fill no)
			(layer "F.Fab")
		)
		(pad "1" thru_hole circle
			(at -1.5875 0 90)
			(size 0.508 0.508)
			(drill 0.254)
			(layers "*.Cu" "*.Mask")
			(remove_unused_layers no)
			(net "GND")
			(clearance 0.127)
			(thermal_gap 0.127)
		)
		(pad "2" thru_hole circle
			(at -0.5715 0 90)
			(size 0.508 0.508)
			(drill 0.254)
			(layers "*.Cu" "*.Mask")
			(remove_unused_layers no)
			(net "PHY_SCC_A_TO_DRV_A_34_DP")
			(clearance 0.127)
			(thermal_gap 0.127)
		)
		(pad "3" thru_hole circle
			(at 0.5715 0 90)
			(size 0.508 0.508)
			(drill 0.254)
			(layers "*.Cu" "*.Mask")
			(remove_unused_layers no)
			(net "PHY_SCC_A_TO_DRV_A_34_DN")
			(clearance 0.127)
			(thermal_gap 0.127)
		)
		(pad "4" thru_hole circle
			(at 1.5875 0 90)
			(size 0.508 0.508)
			(drill 0.254)
			(layers "*.Cu" "*.Mask")
			(remove_unused_layers no)
			(net "GND")
			(clearance 0.127)
			(thermal_gap 0.127)
		)
	)
)
